(kicad_pcb
	(version 20260206)
	(generator "pcbnew")
	(generator_version "10.0")
	(general
		(thickness 1.6)
		(legacy_teardrops no)
	)
	(paper "A4")
	(title_block
		(title "Bryce Canyon_IOM_M2_16342-2_OCP.brd")
		(comment 1 "Bryce Canyon / footprints 103-109 of 1146")
	)
	(layers
		(0 "F.Cu" signal "TOP")
		(4 "In1.Cu" signal "L2GND")
		(6 "In2.Cu" signal "L3")
		(8 "In3.Cu" signal "L4VCC")
		(10 "In4.Cu" signal "L5VCC")
		(12 "In5.Cu" signal "L6")
		(14 "In6.Cu" signal "L7GND")
		(2 "B.Cu" signal "BOTTOM")
		(9 "F.Adhes" user "F.Adhesive")
		(11 "B.Adhes" user "B.Adhesive")
		(13 "F.Paste" user "Package Geometry/Pastemask Top")
		(15 "B.Paste" user "Package Geometry/Pastemask Bottom")
		(5 "F.SilkS" user "Ref Des/Silkscreen Top")
		(7 "B.SilkS" user "Ref Des/Silkscreen Bottom")
		(1 "F.Mask" user "Board Geometry/Soldermask Top")
		(3 "B.Mask" user "Board Geometry/Soldermask Bottom")
		(17 "Dwgs.User" user "User.Drawings")
		(19 "Cmts.User" user "User.Comments")
		(21 "Eco1.User" user "User.Eco1")
		(23 "Eco2.User" user "User.Eco2")
		(25 "Edge.Cuts" user "Board Geometry/Outline")
		(27 "Margin" user)
		(31 "F.CrtYd" user "Package Geometry/Place Bound Top")
		(29 "B.CrtYd" user "Package Geometry/Place Bound Bottom")
		(35 "F.Fab" user "Ref Des/Assembly Top")
		(33 "B.Fab" user "Ref Des/Assembly Bottom")
	)
	(footprint ""
		(layer "F.Cu")
		(at 16.013684 -164.5539 90)
		(property "Reference" "R531"
			(at 0 0 90)
			(layer "F.SilkS")
			(hide yes)
			(effects
				(font
					(size 1.27 1.27)
				)
			)
		)
		(property "Value" "4K99R2F-L-GP"
			(at 0.064008 -3.993896 90)
			(unlocked yes)
			(layer "F.Fab")
			(hide yes)
			(effects
				(font
					(size 1.016 1.016)
					(thickness 0.1524)
				)
			)
		)
		(property "Device Type" "R402H16"
			(at 0.064008 -5.517896 90)
			(unlocked yes)
			(layer "F.Fab")
			(hide yes)
			(effects
				(font
					(size 1.016 1.016)
					(thickness 0.1524)
				)
			)
		)
		(duplicate_pad_numbers_are_jumpers no)
		(fp_line
			(start 0.508 -0.9398)
			(end -0.508 -0.9398)
			(stroke
				(width 0.1524)
				(type default)
			)
			(layer "F.SilkS")
		)
		(fp_line
			(start -0.508 -0.9398)
			(end -0.508 0.9398)
			(stroke
				(width 0.1524)
				(type default)
			)
			(layer "F.SilkS")
		)
		(fp_rect
			(start -0.508 0.9398)
			(end 0.508 -0.9398)
			(stroke
				(width 0)
				(type default)
			)
			(fill no)
			(layer "F.CrtYd")
		)
		(fp_rect
			(start -0.508 0.9398)
			(end 0.508 -0.9398)
			(stroke
				(width 0)
				(type default)
			)
			(fill no)
			(layer "F.Fab")
		)
		(pad "1" smd custom
			(at 0 -0.4445 90)
			(size 0.1397 0.1397)
			(layers "F.Cu" "F.Mask" "F.Paste")
			(net "TPS74801_P1V2_STBY_FB")
			(options
				(clearance outline)
				(anchor circle)
			)
			(primitives
				(gr_poly
					(pts
						(arc
							(start -0.1778 -0.2794)
							(mid -0.249642 -0.249642)
							(end -0.2794 -0.1778)
						)
						(arc
							(start -0.2794 0.1778)
							(mid -0.249642 0.249642)
							(end -0.1778 0.2794)
						)
						(arc
							(start 0.1778 0.2794)
							(mid 0.249642 0.249642)
							(end 0.2794 0.1778)
						)
						(arc
							(start 0.2794 -0.1778)
							(mid 0.249642 -0.249642)
							(end 0.1778 -0.2794)
						)
					)
					(width 0)
					(fill yes)
				)
			)
		)
		(pad "2" smd custom
			(at 0 0.4445 90)
			(size 0.1397 0.1397)
			(layers "F.Cu" "F.Mask" "F.Paste")
			(net "GND")
			(options
				(clearance outline)
				(anchor circle)
			)
			(primitives
				(gr_poly
					(pts
						(arc
							(start -0.1778 -0.2794)
							(mid -0.249642 -0.249642)
							(end -0.2794 -0.1778)
						)
						(arc
							(start -0.2794 0.1778)
							(mid -0.249642 0.249642)
							(end -0.1778 0.2794)
						)
						(arc
							(start 0.1778 0.2794)
							(mid 0.249642 0.249642)
							(end 0.2794 0.1778)
						)
						(arc
							(start 0.2794 -0.1778)
							(mid 0.249642 -0.249642)
							(end 0.1778 -0.2794)
						)
					)
					(width 0)
					(fill yes)
				)
			)
		)
	)
	(footprint ""
		(layer "F.Cu")
		(at 95.06458 -12.2428 90)
		(property "Reference" "D14"
			(at 0 0 90)
			(layer "F.SilkS")
			(hide yes)
			(effects
				(font
					(size 1.27 1.27)
				)
			)
		)
		(property "Value" "PESD5V0S1BL-1-GP"
			(at 1.8923 -1.5621 90)
			(unlocked yes)
			(layer "F.Fab")
			(hide yes)
			(effects
				(font
					(size 1.016 1.016)
					(thickness 0.1524)
				)
			)
		)
		(property "Device Type" "SOD882-10D6-1H20"
			(at 1.8923 -3.0861 90)
			(unlocked yes)
			(layer "F.Fab")
			(hide yes)
			(effects
				(font
					(size 1.016 1.016)
					(thickness 0.1524)
				)
			)
		)
		(duplicate_pad_numbers_are_jumpers no)
		(fp_line
			(start -0.3048 -0.9271)
			(end 0.3048 -0.9271)
			(stroke
				(width 0.254)
				(type default)
			)
			(layer "F.SilkS")
		)
		(fp_rect
			(start -0.2921 0.4953)
			(end 0.2921 -0.4953)
			(stroke
				(width 0)
				(type default)
			)
			(fill no)
			(layer "F.CrtYd")
		)
		(fp_poly
			(pts
				(xy -0.4318 0.8001) (xy -0.4318 -0.266192) (xy -0.2921 -0.266192) (xy -0.2921 0.4953) (xy 0.2921 0.4953)
				(xy 0.2921 -0.4953) (xy -0.2921 -0.4953) (xy -0.2921 -0.2667) (xy -0.4318 -0.2667) (xy -0.4318 -0.8001)
				(xy 0.4318 -0.8001) (xy 0.4318 0.8001)
			)
			(stroke
				(width 0)
				(type default)
			)
			(fill no)
			(layer "F.CrtYd")
		)
		(fp_rect
			(start -0.4318 0.8001)
			(end 0.4318 -0.8001)
			(stroke
				(width 0)
				(type default)
			)
			(fill no)
			(layer "F.Fab")
		)
		(pad "1" smd custom
			(at 0 -0.4445 90)
			(size 0.1143 0.1143)
			(layers "F.Cu" "F.Mask" "F.Paste")
			(net "I2C_DEBUG_SCL")
			(options
				(clearance outline)
				(anchor circle)
			)
			(primitives
				(gr_poly
					(pts
						(arc
							(start -0.2032 0.2286)
							(mid -0.275042 0.198842)
							(end -0.3048 0.127)
						)
						(arc
							(start -0.3048 -0.127)
							(mid -0.275042 -0.198842)
							(end -0.2032 -0.2286)
						)
						(arc
							(start 0.2032 -0.2286)
							(mid 0.275042 -0.198842)
							(end 0.3048 -0.127)
						)
						(arc
							(start 0.3048 0.127)
							(mid 0.275042 0.198842)
							(end 0.2032 0.2286)
						)
					)
					(width 0)
					(fill yes)
				)
			)
		)
		(pad "2" smd custom
			(at 0 0.4445 90)
			(size 0.1143 0.1143)
			(layers "F.Cu" "F.Mask" "F.Paste")
			(net "GND")
			(options
				(clearance outline)
				(anchor circle)
			)
			(primitives
				(gr_poly
					(pts
						(arc
							(start 0.2032 -0.2286)
							(mid 0.275042 -0.198842)
							(end 0.3048 -0.127)
						)
						(arc
							(start 0.3048 0.127)
							(mid 0.275042 0.198842)
							(end 0.2032 0.2286)
						)
						(arc
							(start -0.2032 0.2286)
							(mid -0.275042 0.198842)
							(end -0.3048 0.127)
						)
						(arc
							(start -0.3048 -0.127)
							(mid -0.275042 -0.198842)
							(end -0.2032 -0.2286)
						)
					)
					(width 0)
					(fill yes)
				)
			)
		)
	)
	(footprint ""
		(layer "F.Cu")
		(at 24.042116 -164.3507 90)
		(property "Reference" "C226"
			(at 0 0 90)
			(layer "F.SilkS")
			(hide yes)
			(effects
				(font
					(size 1.27 1.27)
				)
			)
		)
		(property "Value" "SC10U6D3V5KX-4GP"
			(at -0.0762 -6.1214 90)
			(unlocked yes)
			(layer "F.Fab")
			(hide yes)
			(effects
				(font
					(size 1.016 1.016)
					(thickness 0.1524)
				)
			)
		)
		(property "Device Type" "C805H58"
			(at -0.0762 -8.1534 90)
			(unlocked yes)
			(layer "F.Fab")
			(hide yes)
			(effects
				(font
					(size 1.016 1.016)
					(thickness 0.1524)
				)
			)
		)
		(duplicate_pad_numbers_are_jumpers no)
		(fp_line
			(start 0.635 0)
			(end -0.635 0)
			(stroke
				(width 0.508)
				(type default)
			)
			(layer "F.SilkS")
		)
		(fp_rect
			(start -0.9652 1.778)
			(end 0.9652 -1.778)
			(stroke
				(width 0)
				(type default)
			)
			(fill no)
			(layer "F.CrtYd")
		)
		(fp_poly
			(pts
				(xy -0.9652 -1.778) (xy 0.9652 -1.778) (xy 0.9652 1.778) (xy -0.9652 1.778)
			)
			(stroke
				(width 0)
				(type default)
			)
			(fill no)
			(layer "F.Fab")
		)
		(pad "1" smd rect
			(at 0 -0.9652 90)
			(size 1.397 1.143)
			(layers "F.Cu" "F.Mask" "F.Paste")
			(net "TPS74801_P1V2_STBY_OUT")
		)
		(pad "2" smd rect
			(at 0 0.9652 90)
			(size 1.397 1.143)
			(layers "F.Cu" "F.Mask" "F.Paste")
			(net "GND")
		)
	)
	(footprint ""
		(layer "F.Cu")
		(at 61.9506 -156.2354)
		(property "Reference" "R335"
			(at 0 0 0)
			(layer "F.SilkS")
			(hide yes)
			(effects
				(font
					(size 1.27 1.27)
				)
			)
		)
		(property "Value" "0R2J-2-GP"
			(at 0.064008 -3.993896 0)
			(unlocked yes)
			(layer "F.Fab")
			(hide yes)
			(effects
				(font
					(size 1.016 1.016)
					(thickness 0.1524)
				)
			)
		)
		(property "Device Type" "R402H16"
			(at 0.064008 -5.517896 0)
			(unlocked yes)
			(layer "F.Fab")
			(hide yes)
			(effects
				(font
					(size 1.016 1.016)
					(thickness 0.1524)
				)
			)
		)
		(duplicate_pad_numbers_are_jumpers no)
		(fp_line
			(start -0.508 -0.9398)
			(end -0.508 0.9398)
			(stroke
				(width 0.1524)
				(type default)
			)
			(layer "F.SilkS")
		)
		(fp_line
			(start 0.508 -0.9398)
			(end -0.508 -0.9398)
			(stroke
				(width 0.1524)
				(type default)
			)
			(layer "F.SilkS")
		)
		(fp_rect
			(start -0.508 0.9398)
			(end 0.508 -0.9398)
			(stroke
				(width 0)
				(type default)
			)
			(fill no)
			(layer "F.CrtYd")
		)
		(fp_rect
			(start -0.508 0.9398)
			(end 0.508 -0.9398)
			(stroke
				(width 0)
				(type default)
			)
			(fill no)
			(layer "F.Fab")
		)
		(pad "1" smd custom
			(at 0 -0.4445)
			(size 0.1397 0.1397)
			(layers "F.Cu" "F.Mask" "F.Paste")
			(net "NCSI_TXD1")
			(options
				(clearance outline)
				(anchor circle)
			)
			(primitives
				(gr_poly
					(pts
						(arc
							(start -0.1778 -0.2794)
							(mid -0.249642 -0.249642)
							(end -0.2794 -0.1778)
						)
						(arc
							(start -0.2794 0.1778)
							(mid -0.249642 0.249642)
							(end -0.1778 0.2794)
						)
						(arc
							(start 0.1778 0.2794)
							(mid 0.249642 0.249642)
							(end 0.2794 0.1778)
						)
						(arc
							(start 0.2794 -0.1778)
							(mid 0.249642 -0.249642)
							(end 0.1778 -0.2794)
						)
					)
					(width 0)
					(fill yes)
				)
			)
		)
		(pad "2" smd custom
			(at 0 0.4445)
			(size 0.1397 0.1397)
			(layers "F.Cu" "F.Mask" "F.Paste")
			(net "NCSI_TXD1_R")
			(options
				(clearance outline)
				(anchor circle)
			)
			(primitives
				(gr_poly
					(pts
						(arc
							(start -0.1778 -0.2794)
							(mid -0.249642 -0.249642)
							(end -0.2794 -0.1778)
						)
						(arc
							(start -0.2794 0.1778)
							(mid -0.249642 0.249642)
							(end -0.1778 0.2794)
						)
						(arc
							(start 0.1778 0.2794)
							(mid 0.249642 0.249642)
							(end 0.2794 0.1778)
						)
						(arc
							(start 0.2794 -0.1778)
							(mid 0.249642 -0.249642)
							(end 0.1778 -0.2794)
						)
					)
					(width 0)
					(fill yes)
				)
			)
		)
	)
	(footprint ""
		(layer "F.Cu")
		(at 70.5104 -149.733 -90)
		(property "Reference" "U30"
			(at 0 0 270)
			(layer "F.SilkS")
			(hide yes)
			(effects
				(font
					(size 1.27 1.27)
				)
			)
		)
		(property "Value" "ICS551MLFT-GP"
			(at -3.707384 -1.5367 270)
			(unlocked yes)
			(layer "F.Fab")
			(hide yes)
			(effects
				(font
					(size 1.016 1.016)
					(thickness 0.1524)
				)
			)
		)
		(property "Device Type" "SOIC8H69"
			(at -3.707384 -3.0607 270)
			(unlocked yes)
			(layer "F.Fab")
			(hide yes)
			(effects
				(font
					(size 1.016 1.016)
					(thickness 0.1524)
				)
			)
		)
		(duplicate_pad_numbers_are_jumpers no)
		(fp_line
			(start -2.6289 3.4417)
			(end -2.6289 1.4732)
			(stroke
				(width 0.381)
				(type default)
			)
			(layer "F.SilkS")
		)
		(fp_line
			(start -2.7432 1.4224)
			(end -2.6416 1.4224)
			(stroke
				(width 0.1524)
				(type default)
			)
			(layer "F.SilkS")
		)
		(fp_line
			(start -2.7432 1.4224)
			(end 2.1336 1.4224)
			(stroke
				(width 0.1524)
				(type default)
			)
			(layer "F.SilkS")
		)
		(fp_line
			(start 2.1336 1.4224)
			(end 2.1336 -1.4224)
			(stroke
				(width 0.1524)
				(type default)
			)
			(layer "F.SilkS")
		)
		(fp_line
			(start -2.1844 -0.0508)
			(end -2.7178 0.508)
			(stroke
				(width 0.1524)
				(type default)
			)
			(layer "F.SilkS")
		)
		(fp_line
			(start -2.7178 -0.508)
			(end -2.1844 -0.0508)
			(stroke
				(width 0.1524)
				(type default)
			)
			(layer "F.SilkS")
		)
		(fp_line
			(start -2.7432 -1.4224)
			(end -2.7432 1.4224)
			(stroke
				(width 0.1524)
				(type default)
			)
			(layer "F.SilkS")
		)
		(fp_line
			(start 2.1336 -1.4224)
			(end -2.7432 -1.4224)
			(stroke
				(width 0.1524)
				(type default)
			)
			(layer "F.SilkS")
		)
		(fp_poly
			(pts
				(xy -2.2098 -1.4224) (xy -2.2098 1.4224) (xy 2.2098 1.4224) (xy 2.2098 -1.4224)
			)
			(stroke
				(width 0)
				(type default)
			)
			(fill yes)
			(layer "F.SilkS")
		)
		(fp_rect
			(start -2.450084 2.999994)
			(end 2.450084 -2.999994)
			(stroke
				(width 0)
				(type default)
			)
			(fill no)
			(layer "F.CrtYd")
		)
		(fp_poly
			(pts
				(xy -2.8194 3.6322) (xy -2.8194 -3.6322) (xy 2.8194 -3.6322) (xy 2.8194 1.18364) (xy 2.450084 1.18364)
				(xy 2.450084 -2.999994) (xy -2.450084 -2.999994) (xy -2.450084 2.999994) (xy 2.450084 2.999994)
				(xy 2.450084 1.18618) (xy 2.8194 1.18618) (xy 2.8194 3.6322)
			)
			(stroke
				(width 0)
				(type default)
			)
			(fill no)
			(layer "F.CrtYd")
		)
		(fp_rect
			(start -2.8194 3.6322)
			(end 2.8194 -3.6322)
			(stroke
				(width 0)
				(type default)
			)
			(fill no)
			(layer "F.Fab")
		)
		(pad "1" smd rect
			(at -1.905 2.54 270)
			(size 0.635 1.651)
			(layers "F.Cu" "F.Mask" "F.Paste")
			(net "50M_CLK_OUT_R")
		)
		(pad "2" smd rect
			(at -0.635 2.54 270)
			(size 0.635 1.651)
			(layers "F.Cu" "F.Mask" "F.Paste")
			(net "U30_Q1")
		)
		(pad "3" smd rect
			(at 0.635 2.54 270)
			(size 0.635 1.651)
			(layers "F.Cu" "F.Mask" "F.Paste")
			(net "Net_533")
		)
		(pad "4" smd rect
			(at 1.905 2.54 270)
			(size 0.635 1.651)
			(layers "F.Cu" "F.Mask" "F.Paste")
			(net "NCSI_RCLK_R")
		)
		(pad "5" smd rect
			(at 1.905 -2.54 270)
			(size 0.635 1.651)
			(layers "F.Cu" "F.Mask" "F.Paste")
			(net "Net_534")
		)
		(pad "6" smd rect
			(at 0.635 -2.54 270)
			(size 0.635 1.651)
			(layers "F.Cu" "F.Mask" "F.Paste")
			(net "GND")
		)
		(pad "7" smd rect
			(at -0.635 -2.54 270)
			(size 0.635 1.651)
			(layers "F.Cu" "F.Mask" "F.Paste")
			(net "P3V3_STBY")
		)
		(pad "8" smd rect
			(at -1.905 -2.54 270)
			(size 0.635 1.651)
			(layers "F.Cu" "F.Mask" "F.Paste")
			(net "50M_CLK_OE")
		)
	)
	(footprint ""
		(layer "F.Cu")
		(at 78.5114 -172.466 180)
		(property "Reference" "R504"
			(at 0 0 180)
			(layer "F.SilkS")
			(hide yes)
			(effects
				(font
					(size 1.27 1.27)
				)
			)
		)
		(property "Value" "0R5J-5-GP"
			(at 0 -8.9535 180)
			(unlocked yes)
			(layer "F.Fab")
			(hide yes)
			(effects
				(font
					(size 1.27 1.016)
					(thickness 0.1524)
				)
			)
		)
		(property "Device Type" "R805H24"
			(at 0 -10.6299 180)
			(unlocked yes)
			(layer "F.Fab")
			(hide yes)
			(effects
				(font
					(size 1.27 1.016)
					(thickness 0.1524)
				)
			)
		)
		(duplicate_pad_numbers_are_jumpers no)
		(fp_line
			(start 0.889 1.7018)
			(end 0.889 -0.508)
			(stroke
				(width 0.1524)
				(type default)
			)
			(layer "F.SilkS")
		)
		(fp_line
			(start 0.889 -1.7018)
			(end 0.889 -0.381)
			(stroke
				(width 0.1524)
				(type default)
			)
			(layer "F.SilkS")
		)
		(fp_line
			(start 0.889 -1.7018)
			(end -0.889 -1.7018)
			(stroke
				(width 0.1524)
				(type default)
			)
			(layer "F.SilkS")
		)
		(fp_line
			(start -0.889 1.7018)
			(end 0.889 1.7018)
			(stroke
				(width 0.1524)
				(type default)
			)
			(layer "F.SilkS")
		)
		(fp_line
			(start -0.889 0.0762)
			(end -0.889 1.7018)
			(stroke
				(width 0.1524)
				(type default)
			)
			(layer "F.SilkS")
		)
		(fp_line
			(start -0.889 -1.7018)
			(end -0.889 0.2794)
			(stroke
				(width 0.1524)
				(type default)
			)
			(layer "F.SilkS")
		)
		(fp_poly
			(pts
				(xy 0.9652 -1.778) (xy 0.9652 1.778) (xy -0.9652 1.778) (xy -0.9652 -1.778)
			)
			(stroke
				(width 0)
				(type default)
			)
			(fill no)
			(layer "F.CrtYd")
		)
		(fp_rect
			(start -0.9652 1.778)
			(end 0.9652 -1.778)
			(stroke
				(width 0)
				(type default)
			)
			(fill no)
			(layer "F.Fab")
		)
		(pad "1" smd rect
			(at 0 -0.9652 180)
			(size 1.397 1.143)
			(layers "F.Cu" "F.Mask" "F.Paste")
			(net "P2V5_STBY")
		)
		(pad "2" smd rect
			(at 0 0.9652 180)
			(size 1.397 1.143)
			(layers "F.Cu" "F.Mask" "F.Paste")
			(net "TPS74801_P2V5_STBY_OUT")
		)
	)
	(footprint ""
		(layer "F.Cu")
		(at 27.419046 -153.381456 -90)
		(property "Reference" "R771"
			(at 0 0 270)
			(layer "F.SilkS")
			(hide yes)
			(effects
				(font
					(size 1.27 1.27)
				)
			)
		)
		(property "Value" "0R2J-2-GP"
			(at 0.064008 -3.993896 270)
			(unlocked yes)
			(layer "F.Fab")
			(hide yes)
			(effects
				(font
					(size 1.016 1.016)
					(thickness 0.1524)
				)
			)
		)
		(property "Device Type" "R402H16"
			(at 0.064008 -5.517896 270)
			(unlocked yes)
			(layer "F.Fab")
			(hide yes)
			(effects
				(font
					(size 1.016 1.016)
					(thickness 0.1524)
				)
			)
		)
		(duplicate_pad_numbers_are_jumpers no)
		(fp_line
			(start -0.508 -0.9398)
			(end -0.508 0.9398)
			(stroke
				(width 0.1524)
				(type default)
			)
			(layer "F.SilkS")
		)
		(fp_line
			(start 0.508 -0.9398)
			(end -0.508 -0.9398)
			(stroke
				(width 0.1524)
				(type default)
			)
			(layer "F.SilkS")
		)
		(fp_rect
			(start -0.508 0.9398)
			(end 0.508 -0.9398)
			(stroke
				(width 0)
				(type default)
			)
			(fill no)
			(layer "F.CrtYd")
		)
		(fp_rect
			(start -0.508 0.9398)
			(end 0.508 -0.9398)
			(stroke
				(width 0)
				(type default)
			)
			(fill no)
			(layer "F.Fab")
		)
		(pad "1" smd custom
			(at 0 -0.4445 270)
			(size 0.1397 0.1397)
			(layers "F.Cu" "F.Mask" "F.Paste")
			(net "DEBUG_GPIO_BMC_R_4")
			(options
				(clearance outline)
				(anchor circle)
			)
			(primitives
				(gr_poly
					(pts
						(arc
							(start -0.1778 -0.2794)
							(mid -0.249642 -0.249642)
							(end -0.2794 -0.1778)
						)
						(arc
							(start -0.2794 0.1778)
							(mid -0.249642 0.249642)
							(end -0.1778 0.2794)
						)
						(arc
							(start 0.1778 0.2794)
							(mid 0.249642 0.249642)
							(end 0.2794 0.1778)
						)
						(arc
							(start 0.2794 -0.1778)
							(mid 0.249642 -0.249642)
							(end 0.1778 -0.2794)
						)
					)
					(width 0)
					(fill yes)
				)
			)
		)
		(pad "2" smd custom
			(at 0 0.4445 270)
			(size 0.1397 0.1397)
			(layers "F.Cu" "F.Mask" "F.Paste")
			(net "DEBUG_GPIO_BMC_4")
			(options
				(clearance outline)
				(anchor circle)
			)
			(primitives
				(gr_poly
					(pts
						(arc
							(start -0.1778 -0.2794)
							(mid -0.249642 -0.249642)
							(end -0.2794 -0.1778)
						)
						(arc
							(start -0.2794 0.1778)
							(mid -0.249642 0.249642)
							(end -0.1778 0.2794)
						)
						(arc
							(start 0.1778 0.2794)
							(mid 0.249642 0.249642)
							(end 0.2794 0.1778)
						)
						(arc
							(start 0.2794 -0.1778)
							(mid 0.249642 -0.249642)
							(end 0.1778 -0.2794)
						)
					)
					(width 0)
					(fill yes)
				)
			)
		)
	)
)
